(kicad_pcb
	(version 20260206)
	(generator "pcbnew")
	(generator_version "10.0")
	(general
		(thickness 1.6)
		(legacy_teardrops no)
	)
	(paper "A4")
	(title_block
		(title "03242023_DA0F0TMBIJ0_F0T_Motherboard_J_brd_V01_OCP.brd")
		(comment 1 "Grand Teton / footprints 3205-3210 of 6105")
	)
	(layers
		(0 "F.Cu" signal "TOP")
		(4 "In1.Cu" signal "GND")
		(6 "In2.Cu" signal "IN1")
		(8 "In3.Cu" signal "GND1")
		(10 "In4.Cu" signal "IN2")
		(12 "In5.Cu" signal "GND2")
		(14 "In6.Cu" signal "IN3")
		(16 "In7.Cu" signal "GND3")
		(18 "In8.Cu" signal "VCC")
		(20 "In9.Cu" signal "VCC1")
		(22 "In10.Cu" signal "GND4")
		(24 "In11.Cu" signal "IN4")
		(26 "In12.Cu" signal "GND5")
		(28 "In13.Cu" signal "IN5")
		(30 "In14.Cu" signal "GND6")
		(32 "In15.Cu" signal "IN6")
		(34 "In16.Cu" signal "GND7")
		(2 "B.Cu" signal "BOTTOM")
		(9 "F.Adhes" user "F.Adhesive")
		(11 "B.Adhes" user "B.Adhesive")
		(13 "F.Paste" user "Package Geometry/Pastemask Top")
		(15 "B.Paste" user "Package Geometry/Pastemask Bottom")
		(5 "F.SilkS" user "Ref Des/Silkscreen Top")
		(7 "B.SilkS" user "Ref Des/Silkscreen Bottom")
		(1 "F.Mask" user "Board Geometry/Soldermask Top")
		(3 "B.Mask" user "Board Geometry/Soldermask Bottom")
		(17 "Dwgs.User" user "User.Drawings")
		(19 "Cmts.User" user "User.Comments")
		(21 "Eco1.User" user "User.Eco1")
		(23 "Eco2.User" user "User.Eco2")
		(25 "Edge.Cuts" user "Board Geometry/Outline")
		(27 "Margin" user)
		(31 "F.CrtYd" user "Package Geometry/Place Bound Top")
		(29 "B.CrtYd" user "Package Geometry/Place Bound Bottom")
		(35 "F.Fab" user "Ref Des/Assembly Top")
		(33 "B.Fab" user "Ref Des/Assembly Bottom")
	)
	(footprint ""
		(layer "F.Cu")
		(at 194.30619 -43.199558 180)
		(property "Reference" "Q125"
			(at 5.05206 1.580388 0)
			(unlocked yes)
			(layer "F.SilkS")
			(effects
				(font
					(size 0.7874 0.5842)
					(thickness 0.1524)
				)
				(justify left)
			)
		)
		(property "Value" ""
			(at 0 0 180)
			(layer "F.Fab")
			(effects
				(font
					(size 1.27 1.27)
				)
			)
		)
		(duplicate_pad_numbers_are_jumpers no)
		(fp_line
			(start 1.332738 1.100074)
			(end -1.332738 1.100074)
			(stroke
				(width 0.1524)
				(type default)
			)
			(layer "F.SilkS")
		)
		(fp_line
			(start 1.332738 -1.100074)
			(end 1.332738 1.100074)
			(stroke
				(width 0.1524)
				(type default)
			)
			(layer "F.SilkS")
		)
		(fp_line
			(start 0.4826 -1.100074)
			(end 1.332738 -1.100074)
			(stroke
				(width 0.1524)
				(type default)
			)
			(layer "F.SilkS")
		)
		(fp_line
			(start 0 -0.541274)
			(end 0.4826 -1.100074)
			(stroke
				(width 0.1524)
				(type default)
			)
			(layer "F.SilkS")
		)
		(fp_line
			(start -0.4826 -1.100074)
			(end 0 -0.541274)
			(stroke
				(width 0.1524)
				(type default)
			)
			(layer "F.SilkS")
		)
		(fp_line
			(start -1.332738 1.100074)
			(end -1.332738 -1.100074)
			(stroke
				(width 0.1524)
				(type default)
			)
			(layer "F.SilkS")
		)
		(fp_line
			(start -1.332738 -1.100074)
			(end -0.4826 -1.100074)
			(stroke
				(width 0.1524)
				(type default)
			)
			(layer "F.SilkS")
		)
		(fp_poly
			(pts
				(xy -1.928114 -1.29413) (xy -1.495552 -0.639064) (xy -2.279142 -0.686054)
			)
			(stroke
				(width 0)
				(type default)
			)
			(fill yes)
			(layer "F.SilkS")
		)
		(fp_line
			(start 0.674878 1.100074)
			(end -0.674878 1.100074)
			(stroke
				(width 0.1)
				(type default)
			)
			(layer "F.Fab")
		)
		(fp_line
			(start 0.674878 -1.100074)
			(end 0.674878 1.100074)
			(stroke
				(width 0.1)
				(type default)
			)
			(layer "F.Fab")
		)
		(fp_line
			(start -0.674878 1.100074)
			(end -0.674878 -1.100074)
			(stroke
				(width 0.1)
				(type default)
			)
			(layer "F.Fab")
		)
		(fp_line
			(start -0.674878 -1.100074)
			(end 0.674878 -1.100074)
			(stroke
				(width 0.1)
				(type default)
			)
			(layer "F.Fab")
		)
		(fp_poly
			(pts
				(xy -2.2352 -0.298958) (xy -2.2352 -1.001014) (xy -1.533144 -0.649986)
			)
			(stroke
				(width 0)
				(type default)
			)
			(fill yes)
			(layer "F.Fab")
		)
		(pad "1" smd rect
			(at -0.94996 -0.649986 270)
			(size 0.4318 0.508)
			(layers "F.Cu" "F.Mask" "F.Paste")
			(net "GND")
		)
		(pad "2" smd rect
			(at -0.94996 0 270)
			(size 0.4318 0.508)
			(layers "F.Cu" "F.Mask" "F.Paste")
			(net "P12V_SCM_EN_R")
		)
		(pad "3" smd rect
			(at -0.94996 0.649986 270)
			(size 0.4318 0.508)
			(layers "F.Cu" "F.Mask" "F.Paste")
			(net "P12V_SCM_UV_R")
		)
		(pad "4" smd rect
			(at 0.94996 0.649986 270)
			(size 0.4318 0.508)
			(layers "F.Cu" "F.Mask" "F.Paste")
			(net "GND")
		)
		(pad "5" smd rect
			(at 0.94996 0 270)
			(size 0.4318 0.508)
			(layers "F.Cu" "F.Mask" "F.Paste")
			(net "P12V_SCM_EN_G")
		)
		(pad "6" smd rect
			(at 0.94996 -0.649986 270)
			(size 0.4318 0.508)
			(layers "F.Cu" "F.Mask" "F.Paste")
			(net "P12V_SCM_EN_G")
		)
	)
	(footprint ""
		(layer "F.Cu")
		(at 172.7835 -358.15778 90)
		(property "Reference" "PR1800"
			(at 0 0 90)
			(layer "F.SilkS")
			(hide yes)
			(effects
				(font
					(size 1.27 1.27)
				)
			)
		)
		(property "Value" ""
			(at 0 0 90)
			(layer "F.Fab")
			(effects
				(font
					(size 1.27 1.27)
				)
			)
		)
		(duplicate_pad_numbers_are_jumpers no)
		(fp_line
			(start 0.7874 -0.4064)
			(end 0.7874 0.4064)
			(stroke
				(width 0.1524)
				(type default)
			)
			(layer "F.SilkS")
		)
		(fp_line
			(start -0.7874 -0.4064)
			(end 0.7874 -0.4064)
			(stroke
				(width 0.1524)
				(type default)
			)
			(layer "F.SilkS")
		)
		(fp_line
			(start 0.7874 0.4064)
			(end -0.7874 0.4064)
			(stroke
				(width 0.1524)
				(type default)
			)
			(layer "F.SilkS")
		)
		(fp_line
			(start -0.7874 0.4064)
			(end -0.7874 -0.4064)
			(stroke
				(width 0.1524)
				(type default)
			)
			(layer "F.SilkS")
		)
		(fp_line
			(start -0.12065 -0.305054)
			(end -0.12065 -0.2794)
			(stroke
				(width 0.1)
				(type default)
			)
			(layer "F.Fab")
		)
		(fp_line
			(start -0.67945 -0.305054)
			(end -0.12065 -0.305054)
			(stroke
				(width 0.1)
				(type default)
			)
			(layer "F.Fab")
		)
		(fp_line
			(start 0.67945 -0.3048)
			(end 0.67945 0.3048)
			(stroke
				(width 0.1)
				(type default)
			)
			(layer "F.Fab")
		)
		(fp_line
			(start 0.12065 -0.3048)
			(end 0.67945 -0.3048)
			(stroke
				(width 0.1)
				(type default)
			)
			(layer "F.Fab")
		)
		(fp_line
			(start 0.12065 -0.2794)
			(end 0.12065 -0.3048)
			(stroke
				(width 0.1)
				(type default)
			)
			(layer "F.Fab")
		)
		(fp_line
			(start -0.12065 -0.2794)
			(end 0.12065 -0.2794)
			(stroke
				(width 0.1)
				(type default)
			)
			(layer "F.Fab")
		)
		(fp_line
			(start 0.120396 0.2794)
			(end -0.12065 0.2794)
			(stroke
				(width 0.1)
				(type default)
			)
			(layer "F.Fab")
		)
		(fp_line
			(start -0.12065 0.2794)
			(end -0.12065 0.3048)
			(stroke
				(width 0.1)
				(type default)
			)
			(layer "F.Fab")
		)
		(fp_line
			(start 0.67945 0.3048)
			(end 0.120396 0.3048)
			(stroke
				(width 0.1)
				(type default)
			)
			(layer "F.Fab")
		)
		(fp_line
			(start 0.120396 0.3048)
			(end 0.120396 0.2794)
			(stroke
				(width 0.1)
				(type default)
			)
			(layer "F.Fab")
		)
		(fp_line
			(start -0.12065 0.3048)
			(end -0.67945 0.3048)
			(stroke
				(width 0.1)
				(type default)
			)
			(layer "F.Fab")
		)
		(fp_line
			(start -0.67945 0.3048)
			(end -0.67945 -0.305054)
			(stroke
				(width 0.1)
				(type default)
			)
			(layer "F.Fab")
		)
		(pad "1" smd circle
			(at -0.40005 0 90)
			(size 0 0)
			(layers "F.Cu" "F.Mask" "F.Paste")
			(net "SW_PVCCFA_EHV_FIVRA_CPU1_BOOT1")
		)
		(pad "2" smd circle
			(at 0.40005 0 90)
			(size 0 0)
			(layers "F.Cu" "F.Mask" "F.Paste")
			(net "SW_PVCCFA_EHV_FIVRA_CPU1_BOOT1_")
		)
	)
	(footprint ""
		(layer "F.Cu")
		(at 320.81216 -26.700988 -90)
		(property "Reference" "R2412"
			(at 0 0 270)
			(layer "F.SilkS")
			(hide yes)
			(effects
				(font
					(size 1.27 1.27)
				)
			)
		)
		(property "Value" ""
			(at 0 0 270)
			(layer "F.Fab")
			(effects
				(font
					(size 1.27 1.27)
				)
			)
		)
		(duplicate_pad_numbers_are_jumpers no)
		(fp_line
			(start -0.7874 0.4064)
			(end -0.7874 -0.4064)
			(stroke
				(width 0.1524)
				(type default)
			)
			(layer "F.SilkS")
		)
		(fp_line
			(start 0.7874 0.4064)
			(end -0.7874 0.4064)
			(stroke
				(width 0.1524)
				(type default)
			)
			(layer "F.SilkS")
		)
		(fp_line
			(start -0.7874 -0.4064)
			(end 0.7874 -0.4064)
			(stroke
				(width 0.1524)
				(type default)
			)
			(layer "F.SilkS")
		)
		(fp_line
			(start 0.7874 -0.4064)
			(end 0.7874 0.4064)
			(stroke
				(width 0.1524)
				(type default)
			)
			(layer "F.SilkS")
		)
		(fp_line
			(start -0.67945 0.3048)
			(end -0.67945 -0.305054)
			(stroke
				(width 0.1)
				(type default)
			)
			(layer "F.Fab")
		)
		(fp_line
			(start -0.12065 0.3048)
			(end -0.67945 0.3048)
			(stroke
				(width 0.1)
				(type default)
			)
			(layer "F.Fab")
		)
		(fp_line
			(start 0.120396 0.3048)
			(end 0.120396 0.2794)
			(stroke
				(width 0.1)
				(type default)
			)
			(layer "F.Fab")
		)
		(fp_line
			(start 0.67945 0.3048)
			(end 0.120396 0.3048)
			(stroke
				(width 0.1)
				(type default)
			)
			(layer "F.Fab")
		)
		(fp_line
			(start -0.12065 0.2794)
			(end -0.12065 0.3048)
			(stroke
				(width 0.1)
				(type default)
			)
			(layer "F.Fab")
		)
		(fp_line
			(start 0.120396 0.2794)
			(end -0.12065 0.2794)
			(stroke
				(width 0.1)
				(type default)
			)
			(layer "F.Fab")
		)
		(fp_line
			(start -0.12065 -0.2794)
			(end 0.12065 -0.2794)
			(stroke
				(width 0.1)
				(type default)
			)
			(layer "F.Fab")
		)
		(fp_line
			(start 0.12065 -0.2794)
			(end 0.12065 -0.3048)
			(stroke
				(width 0.1)
				(type default)
			)
			(layer "F.Fab")
		)
		(fp_line
			(start 0.12065 -0.3048)
			(end 0.67945 -0.3048)
			(stroke
				(width 0.1)
				(type default)
			)
			(layer "F.Fab")
		)
		(fp_line
			(start 0.67945 -0.3048)
			(end 0.67945 0.3048)
			(stroke
				(width 0.1)
				(type default)
			)
			(layer "F.Fab")
		)
		(fp_line
			(start -0.67945 -0.305054)
			(end -0.12065 -0.305054)
			(stroke
				(width 0.1)
				(type default)
			)
			(layer "F.Fab")
		)
		(fp_line
			(start -0.12065 -0.305054)
			(end -0.12065 -0.2794)
			(stroke
				(width 0.1)
				(type default)
			)
			(layer "F.Fab")
		)
		(pad "1" smd circle
			(at -0.40005 0 270)
			(size 0 0)
			(layers "F.Cu" "F.Mask" "F.Paste")
			(net "PWRGD_DSW_PWROK")
		)
		(pad "2" smd circle
			(at 0.40005 0 270)
			(size 0 0)
			(layers "F.Cu" "F.Mask" "F.Paste")
			(net "PWRGD_DSW_PWROK_R3")
		)
	)
	(footprint ""
		(layer "F.Cu")
		(at 101.58349 -336.192368 90)
		(property "Reference" "PC556"
			(at 0 0 90)
			(layer "F.SilkS")
			(hide yes)
			(effects
				(font
					(size 1.27 1.27)
				)
			)
		)
		(property "Value" ""
			(at 0 0 90)
			(layer "F.Fab")
			(effects
				(font
					(size 1.27 1.27)
				)
			)
		)
		(duplicate_pad_numbers_are_jumpers no)
		(fp_line
			(start 0.7874 -0.4064)
			(end 0.7874 0.4064)
			(stroke
				(width 0.1524)
				(type default)
			)
			(layer "F.SilkS")
		)
		(fp_line
			(start -0.7874 -0.4064)
			(end 0.7874 -0.4064)
			(stroke
				(width 0.1524)
				(type default)
			)
			(layer "F.SilkS")
		)
		(fp_line
			(start 0.7874 0.4064)
			(end -0.7874 0.4064)
			(stroke
				(width 0.1524)
				(type default)
			)
			(layer "F.SilkS")
		)
		(fp_line
			(start -0.7874 0.4064)
			(end -0.7874 -0.4064)
			(stroke
				(width 0.1524)
				(type default)
			)
			(layer "F.SilkS")
		)
		(fp_line
			(start -0.12065 -0.305054)
			(end -0.12065 -0.2794)
			(stroke
				(width 0.1)
				(type default)
			)
			(layer "F.Fab")
		)
		(fp_line
			(start -0.67945 -0.305054)
			(end -0.12065 -0.305054)
			(stroke
				(width 0.1)
				(type default)
			)
			(layer "F.Fab")
		)
		(fp_line
			(start 0.67945 -0.3048)
			(end 0.67945 0.3048)
			(stroke
				(width 0.1)
				(type default)
			)
			(layer "F.Fab")
		)
		(fp_line
			(start 0.12065 -0.3048)
			(end 0.67945 -0.3048)
			(stroke
				(width 0.1)
				(type default)
			)
			(layer "F.Fab")
		)
		(fp_line
			(start 0.12065 -0.2794)
			(end 0.12065 -0.3048)
			(stroke
				(width 0.1)
				(type default)
			)
			(layer "F.Fab")
		)
		(fp_line
			(start -0.12065 -0.2794)
			(end 0.12065 -0.2794)
			(stroke
				(width 0.1)
				(type default)
			)
			(layer "F.Fab")
		)
		(fp_line
			(start 0.120396 0.2794)
			(end -0.12065 0.2794)
			(stroke
				(width 0.1)
				(type default)
			)
			(layer "F.Fab")
		)
		(fp_line
			(start -0.12065 0.2794)
			(end -0.12065 0.3048)
			(stroke
				(width 0.1)
				(type default)
			)
			(layer "F.Fab")
		)
		(fp_line
			(start 0.67945 0.3048)
			(end 0.120396 0.3048)
			(stroke
				(width 0.1)
				(type default)
			)
			(layer "F.Fab")
		)
		(fp_line
			(start 0.120396 0.3048)
			(end 0.120396 0.2794)
			(stroke
				(width 0.1)
				(type default)
			)
			(layer "F.Fab")
		)
		(fp_line
			(start -0.12065 0.3048)
			(end -0.67945 0.3048)
			(stroke
				(width 0.1)
				(type default)
			)
			(layer "F.Fab")
		)
		(fp_line
			(start -0.67945 0.3048)
			(end -0.67945 -0.305054)
			(stroke
				(width 0.1)
				(type default)
			)
			(layer "F.Fab")
		)
		(pad "1" smd circle
			(at -0.40005 0 90)
			(size 0 0)
			(layers "F.Cu" "F.Mask" "F.Paste")
			(net "PVCCIN_CPU1_VDD2")
		)
		(pad "2" smd circle
			(at 0.40005 0 90)
			(size 0 0)
			(layers "F.Cu" "F.Mask" "F.Paste")
			(net "GND")
		)
	)
	(footprint ""
		(layer "F.Cu")
		(at 18.8214 -410.7942 90)
		(property "Reference" "R4728"
			(at 0 0 90)
			(layer "F.SilkS")
			(hide yes)
			(effects
				(font
					(size 1.27 1.27)
				)
			)
		)
		(property "Value" ""
			(at 0 0 90)
			(layer "F.Fab")
			(effects
				(font
					(size 1.27 1.27)
				)
			)
		)
		(duplicate_pad_numbers_are_jumpers no)
		(fp_line
			(start 0.7874 -0.406146)
			(end 0.7874 0.406146)
			(stroke
				(width 0.1524)
				(type default)
			)
			(layer "F.SilkS")
		)
		(fp_line
			(start -0.7874 -0.406146)
			(end 0.7874 -0.406146)
			(stroke
				(width 0.1524)
				(type default)
			)
			(layer "F.SilkS")
		)
		(fp_line
			(start 0.7874 0.406146)
			(end -0.7874 0.406146)
			(stroke
				(width 0.1524)
				(type default)
			)
			(layer "F.SilkS")
		)
		(fp_line
			(start -0.7874 0.406146)
			(end -0.7874 -0.406146)
			(stroke
				(width 0.1524)
				(type default)
			)
			(layer "F.SilkS")
		)
		(fp_line
			(start -0.12065 -0.305054)
			(end -0.12065 -0.2794)
			(stroke
				(width 0.1)
				(type default)
			)
			(layer "F.Fab")
		)
		(fp_line
			(start -0.67945 -0.305054)
			(end -0.12065 -0.305054)
			(stroke
				(width 0.1)
				(type default)
			)
			(layer "F.Fab")
		)
		(fp_line
			(start 0.67945 -0.3048)
			(end 0.67945 0.3048)
			(stroke
				(width 0.1)
				(type default)
			)
			(layer "F.Fab")
		)
		(fp_line
			(start 0.120396 -0.3048)
			(end 0.67945 -0.3048)
			(stroke
				(width 0.1)
				(type default)
			)
			(layer "F.Fab")
		)
		(fp_line
			(start 0.12065 -0.2794)
			(end 0.120396 -0.3048)
			(stroke
				(width 0.1)
				(type default)
			)
			(layer "F.Fab")
		)
		(fp_line
			(start -0.12065 -0.2794)
			(end 0.12065 -0.2794)
			(stroke
				(width 0.1)
				(type default)
			)
			(layer "F.Fab")
		)
		(fp_line
			(start 0.120396 0.2794)
			(end -0.12065 0.2794)
			(stroke
				(width 0.1)
				(type default)
			)
			(layer "F.Fab")
		)
		(fp_line
			(start -0.12065 0.2794)
			(end -0.120396 0.3048)
			(stroke
				(width 0.1)
				(type default)
			)
			(layer "F.Fab")
		)
		(fp_line
			(start 0.67945 0.3048)
			(end 0.120396 0.3048)
			(stroke
				(width 0.1)
				(type default)
			)
			(layer "F.Fab")
		)
		(fp_line
			(start 0.120396 0.3048)
			(end 0.120396 0.2794)
			(stroke
				(width 0.1)
				(type default)
			)
			(layer "F.Fab")
		)
		(fp_line
			(start -0.120396 0.3048)
			(end -0.67945 0.3048)
			(stroke
				(width 0.1)
				(type default)
			)
			(layer "F.Fab")
		)
		(fp_line
			(start -0.67945 0.3048)
			(end -0.67945 -0.305054)
			(stroke
				(width 0.1)
				(type default)
			)
			(layer "F.Fab")
		)
		(pad "1" smd circle
			(at -0.40005 0 90)
			(size 0 0)
			(layers "F.Cu" "F.Mask" "F.Paste")
			(net "PRSNT_SWB_ISO_N")
		)
		(pad "2" smd circle
			(at 0.40005 0 90)
			(size 0 0)
			(layers "F.Cu" "F.Mask" "F.Paste")
			(net "PRSNT_SWB_ISO_R1_N")
		)
	)
	(footprint ""
		(layer "F.Cu")
		(at 228.764592 -124.281946 180)
		(property "Reference" "R566"
			(at 0 0 180)
			(layer "F.SilkS")
			(hide yes)
			(effects
				(font
					(size 1.27 1.27)
				)
			)
		)
		(property "Value" ""
			(at 0 0 180)
			(layer "F.Fab")
			(effects
				(font
					(size 1.27 1.27)
				)
			)
		)
		(duplicate_pad_numbers_are_jumpers no)
		(fp_line
			(start 0.7874 -0.4064)
			(end 0.7874 0.089154)
			(stroke
				(width 0.1524)
				(type default)
			)
			(layer "F.SilkS")
		)
		(fp_line
			(start 0.520192 0.4064)
			(end -0.429768 0.4064)
			(stroke
				(width 0.1524)
				(type default)
			)
			(layer "F.SilkS")
		)
		(fp_line
			(start -0.7874 0.063754)
			(end -0.7874 -0.4064)
			(stroke
				(width 0.1524)
				(type default)
			)
			(layer "F.SilkS")
		)
		(fp_line
			(start -0.7874 -0.4064)
			(end 0.7874 -0.4064)
			(stroke
				(width 0.1524)
				(type default)
			)
			(layer "F.SilkS")
		)
		(fp_line
			(start 0.67945 0.3048)
			(end 0.120396 0.3048)
			(stroke
				(width 0.1)
				(type default)
			)
			(layer "F.Fab")
		)
		(fp_line
			(start 0.67945 -0.3048)
			(end 0.67945 0.3048)
			(stroke
				(width 0.1)
				(type default)
			)
			(layer "F.Fab")
		)
		(fp_line
			(start 0.12065 -0.2794)
			(end 0.12065 -0.3048)
			(stroke
				(width 0.1)
				(type default)
			)
			(layer "F.Fab")
		)
		(fp_line
			(start 0.12065 -0.3048)
			(end 0.67945 -0.3048)
			(stroke
				(width 0.1)
				(type default)
			)
			(layer "F.Fab")
		)
		(fp_line
			(start 0.120396 0.3048)
			(end 0.120396 0.2794)
			(stroke
				(width 0.1)
				(type default)
			)
			(layer "F.Fab")
		)
		(fp_line
			(start 0.120396 0.2794)
			(end -0.12065 0.2794)
			(stroke
				(width 0.1)
				(type default)
			)
			(layer "F.Fab")
		)
		(fp_line
			(start -0.12065 0.3048)
			(end -0.67945 0.3048)
			(stroke
				(width 0.1)
				(type default)
			)
			(layer "F.Fab")
		)
		(fp_line
			(start -0.12065 0.2794)
			(end -0.12065 0.3048)
			(stroke
				(width 0.1)
				(type default)
			)
			(layer "F.Fab")
		)
		(fp_line
			(start -0.12065 -0.2794)
			(end 0.12065 -0.2794)
			(stroke
				(width 0.1)
				(type default)
			)
			(layer "F.Fab")
		)
		(fp_line
			(start -0.12065 -0.305054)
			(end -0.12065 -0.2794)
			(stroke
				(width 0.1)
				(type default)
			)
			(layer "F.Fab")
		)
		(fp_line
			(start -0.67945 0.3048)
			(end -0.67945 -0.305054)
			(stroke
				(width 0.1)
				(type default)
			)
			(layer "F.Fab")
		)
		(fp_line
			(start -0.67945 -0.305054)
			(end -0.12065 -0.305054)
			(stroke
				(width 0.1)
				(type default)
			)
			(layer "F.Fab")
		)
		(pad "1" smd circle
			(at -0.40005 0 180)
			(size 0 0)
			(layers "F.Cu" "F.Mask" "F.Paste")
			(net "CLK_100M_OCP_SFF_1_R_DN")
		)
		(pad "2" smd circle
			(at 0.40005 0 180)
			(size 0 0)
			(layers "F.Cu" "F.Mask" "F.Paste")
			(net "CLK_100M_OCP_SFF_1_DN")
		)
	)
)
